(kicad_pcb
	(version 20241229)
	(generator "pcbnew")
	(generator_version "9.0")
	(general
		(thickness 1.294)
		(legacy_teardrops no)
	)
	(paper "A3")
	(title_block
		(title "Kintex 410T devboard")
		(date "2024-04-03")
		(rev "1.1.2")
		(comment 9 "footprints 736-740 of 975")
	)
	(layers
		(0 "F.Cu" mixed)
		(4 "In1.Cu" power)
		(6 "In2.Cu" power)
		(8 "In3.Cu" mixed)
		(10 "In4.Cu" power)
		(12 "In5.Cu" mixed)
		(14 "In6.Cu" power)
		(16 "In7.Cu" mixed)
		(18 "In8.Cu" power)
		(2 "B.Cu" mixed)
		(9 "F.Adhes" user "F.Adhesive")
		(11 "B.Adhes" user "B.Adhesive")
		(13 "F.Paste" user)
		(15 "B.Paste" user)
		(5 "F.SilkS" user "F.Silkscreen")
		(7 "B.SilkS" user "B.Silkscreen")
		(1 "F.Mask" user)
		(3 "B.Mask" user)
		(17 "Dwgs.User" user "User.Drawings")
		(19 "Cmts.User" user "User.Comments")
		(21 "Eco1.User" user "User.Eco1")
		(23 "Eco2.User" user "User.Eco2")
		(25 "Edge.Cuts" user)
		(27 "Margin" user)
		(31 "F.CrtYd" user "F.Courtyard")
		(29 "B.CrtYd" user "B.Courtyard")
		(35 "F.Fab" user)
		(33 "B.Fab" user)
	)
	(footprint "antmicro-footprints:LED_0603_1608Metric_G"
		(layer "B.Cu")
		(at 268.301 146.85 180)
		(descr "LED SMD 0603 Green")
		(tags "LED SMD 0603 Green")
		(property "Reference" "D12"
			(at 4.101 -0.3 0)
			(layer "B.SilkS")
			(effects
				(font
					(size 0.7 0.7)
					(thickness 0.15)
				)
				(justify left bottom mirror)
			)
		)
		(property "Value" "LED_G_0603_KP-1608CGCK"
			(at 0 -1.6 0)
			(layer "B.Fab")
			(effects
				(font
					(size 0.7 0.7)
					(thickness 0.15)
				)
				(justify left bottom mirror)
			)
		)
		(property "Description" "LED, Green, SMD, 0603, 20 mA, 2.1 V, 570 nm"
			(at 0 0 180)
			(layer "F.Fab")
			(hide yes)
			(effects
				(font
					(size 1.27 1.27)
					(thickness 0.15)
				)
			)
		)
		(property "Author" "Antmicro"
			(at 536.602 293.7 0)
			(layer "B.Fab")
			(hide yes)
			(effects
				(font
					(size 1 1)
					(thickness 0.15)
				)
				(justify mirror)
			)
		)
		(property "Color" "Green"
			(at 536.602 293.7 0)
			(layer "B.Fab")
			(hide yes)
			(effects
				(font
					(size 1 1)
					(thickness 0.15)
				)
				(justify mirror)
			)
		)
		(property "License" "Apache-2.0"
			(at 536.602 293.7 0)
			(layer "B.Fab")
			(hide yes)
			(effects
				(font
					(size 1 1)
					(thickness 0.15)
				)
				(justify mirror)
			)
		)
		(property "MPN" "KP-1608CGCK"
			(at 536.602 293.7 0)
			(layer "B.Fab")
			(hide yes)
			(effects
				(font
					(size 1 1)
					(thickness 0.15)
				)
				(justify mirror)
			)
		)
		(property "Manufacturer" "Kingbright"
			(at 536.602 293.7 0)
			(layer "B.Fab")
			(hide yes)
			(effects
				(font
					(size 1 1)
					(thickness 0.15)
				)
				(justify mirror)
			)
		)
		(sheetname "Power supply")
		(sheetfile "power-supply.kicad_sch")
		(attr smd)
		(fp_line
			(start 0.22 0.35)
			(end -0.22 0.35)
			(stroke
				(width 0.15)
				(type solid)
			)
			(layer "B.SilkS")
		)
		(fp_line
			(start 0.22 -0.35)
			(end -0.22 -0.35)
			(stroke
				(width 0.15)
				(type solid)
			)
			(layer "B.SilkS")
		)
		(fp_line
			(start 0.105328 -0.001008)
			(end 0.24 -0.001)
			(stroke
				(width 0.1)
				(type solid)
			)
			(layer "B.SilkS")
		)
		(fp_line
			(start 0.105328 -0.201008)
			(end 0.105328 0.198992)
			(stroke
				(width 0.1)
				(type solid)
			)
			(layer "B.SilkS")
		)
		(fp_line
			(start 0.105328 -0.201008)
			(end -0.094672 -0.001008)
			(stroke
				(width 0.1)
				(type solid)
			)
			(layer "B.SilkS")
		)
		(fp_line
			(start -0.094672 -0.001008)
			(end 0.105328 0.198992)
			(stroke
				(width 0.1)
				(type solid)
			)
			(layer "B.SilkS")
		)
		(fp_line
			(start -0.094672 -0.001008)
			(end -0.24 -0.001008)
			(stroke
				(width 0.1)
				(type solid)
			)
			(layer "B.SilkS")
		)
		(fp_line
			(start -0.094672 -0.201008)
			(end -0.094672 0.198992)
			(stroke
				(width 0.1)
				(type solid)
			)
			(layer "B.SilkS")
		)
		(fp_line
			(start -1.18 0.319)
			(end -1.18 -0.321)
			(stroke
				(width 0.15)
				(type solid)
			)
			(layer "B.SilkS")
		)
		(fp_rect
			(start 1.25 -0.65)
			(end -1.25 0.65)
			(stroke
				(width 0.05)
				(type solid)
			)
			(fill no)
			(layer "B.CrtYd")
		)
		(fp_line
			(start 0.599 0)
			(end 0.201 0)
			(stroke
				(width 0.15)
				(type solid)
			)
			(layer "B.Fab")
		)
		(fp_line
			(start 0.201 0.202)
			(end -0.101 0)
			(stroke
				(width 0.15)
				(type solid)
			)
			(layer "B.Fab")
		)
		(fp_line
			(start 0.201 0)
			(end 0.201 0.202)
			(stroke
				(width 0.15)
				(type solid)
			)
			(layer "B.Fab")
		)
		(fp_line
			(start 0.201 -0.2)
			(end 0.201 0)
			(stroke
				(width 0.15)
				(type solid)
			)
			(layer "B.Fab")
		)
		(fp_line
			(start -0.101 0)
			(end 0.201 -0.2)
			(stroke
				(width 0.15)
				(type solid)
			)
			(layer "B.Fab")
		)
		(fp_line
			(start -0.199 0.202)
			(end -0.199 -0.1)
			(stroke
				(width 0.15)
				(type solid)
			)
			(layer "B.Fab")
		)
		(fp_line
			(start -0.199 0)
			(end -0.597 0)
			(stroke
				(width 0.15)
				(type solid)
			)
			(layer "B.Fab")
		)
		(fp_line
			(start -0.199 -0.2)
			(end -0.199 -0.1)
			(stroke
				(width 0.15)
				(type solid)
			)
			(layer "B.Fab")
		)
		(fp_rect
			(start 0.848 -0.4)
			(end -0.85 0.402)
			(stroke
				(width 0.15)
				(type solid)
			)
			(fill no)
			(layer "B.Fab")
		)
		(pad "1" smd roundrect
			(at -0.7 0)
			(size 0.8 1)
			(layers "B.Cu" "B.Mask" "B.Paste")
			(roundrect_rratio 0.2)
			(net 771 "/Power supply/PD_PWR_OK3")
			(pinfunction "C")
			(pintype "passive")
		)
		(pad "2" smd roundrect
			(at 0.7 0)
			(size 0.8 1)
			(layers "B.Cu" "B.Mask" "B.Paste")
			(roundrect_rratio 0.2)
			(net 755 "Net-(D12-A)")
			(pinfunction "A")
			(pintype "passive")
		)
	)
	(footprint "antmicro-footprints:R_0402_1005Metric"
		(layer "B.Cu")
		(at 158.245001 85.165001)
		(descr "Resistor SMD 0402")
		(tags "resistor SMD 0402")
		(property "Reference" "R273"
			(at -0.820001 0.309999 180)
			(layer "B.SilkS")
			(effects
				(font
					(size 0.7 0.7)
					(thickness 0.15)
				)
				(justify left bottom mirror)
			)
		)
		(property "Value" "R_33R_0402"
			(at 0 -1.4 180)
			(layer "B.Fab")
			(effects
				(font
					(size 0.7 0.7)
					(thickness 0.15)
				)
				(justify left bottom mirror)
			)
		)
		(property "Description" "SMD Chip Resistor, 33 ohm, ± 1%, 62.5 mW, 0402 [1005 Metric], Thick Film, General Purpose"
			(at 0 0 0)
			(layer "F.Fab")
			(hide yes)
			(effects
				(font
					(size 1.27 1.27)
					(thickness 0.15)
				)
			)
		)
		(property "Author" "Antmicro"
			(at 0 0 0)
			(layer "B.Fab")
			(hide yes)
			(effects
				(font
					(size 1 1)
					(thickness 0.15)
				)
				(justify mirror)
			)
		)
		(property "License" "Apache-2.0"
			(at 0 0 0)
			(layer "B.Fab")
			(hide yes)
			(effects
				(font
					(size 1 1)
					(thickness 0.15)
				)
				(justify mirror)
			)
		)
		(property "MPN" "CR0402-FX-33R0GLF"
			(at 0 0 0)
			(layer "B.Fab")
			(hide yes)
			(effects
				(font
					(size 1 1)
					(thickness 0.15)
				)
				(justify mirror)
			)
		)
		(property "Manufacturer" "Bourns"
			(at 0 0 0)
			(layer "B.Fab")
			(hide yes)
			(effects
				(font
					(size 1 1)
					(thickness 0.15)
				)
				(justify mirror)
			)
		)
		(property "Tolerance" "1%"
			(at 0 0 0)
			(layer "B.Fab")
			(hide yes)
			(effects
				(font
					(size 1 1)
					(thickness 0.15)
				)
				(justify mirror)
			)
		)
		(property "Val" "33R"
			(at 0 0 0)
			(layer "B.Fab")
			(hide yes)
			(effects
				(font
					(size 1 1)
					(thickness 0.15)
				)
				(justify mirror)
			)
		)
		(sheetname "FMC+ HSPC")
		(sheetfile "fmc-hspc.kicad_sch")
		(attr smd)
		(fp_rect
			(start -0.925 0.47)
			(end 0.925 -0.47)
			(stroke
				(width 0.05)
				(type default)
			)
			(fill no)
			(layer "B.CrtYd")
		)
		(fp_rect
			(start -0.5 0.25)
			(end 0.5 -0.25)
			(stroke
				(width 0.15)
				(type solid)
			)
			(fill no)
			(layer "B.Fab")
		)
		(pad "1" smd roundrect
			(at -0.48 0)
			(size 0.59 0.64)
			(layers "B.Cu" "B.Mask" "B.Paste")
			(roundrect_rratio 0.25)
			(net 593 "/FMC+ HSPC/GTR_REFCLK2_R_P")
			(pintype "passive")
		)
		(pad "2" smd roundrect
			(at 0.48 0)
			(size 0.59 0.64)
			(layers "B.Cu" "B.Mask" "B.Paste")
			(roundrect_rratio 0.25)
			(net 594 "/FMC+ HSPC/GTX116.REFCLK0_P")
			(pintype "passive")
		)
	)
	(footprint "antmicro-footprints:C_0402_1005Metric"
		(layer "B.Cu")
		(at 165.745001 125.685001 180)
		(descr "Capacitor SMD 0402")
		(tags "capacitor SMD 0402")
		(property "Reference" "C296"
			(at 0.820001 -0.364999 0)
			(layer "B.SilkS")
			(effects
				(font
					(size 0.7 0.7)
					(thickness 0.15)
				)
				(justify left bottom mirror)
			)
		)
		(property "Value" "C_100n_0402"
			(at 0 -1.169 0)
			(layer "B.Fab")
			(effects
				(font
					(size 0.7 0.7)
					(thickness 0.15)
				)
				(justify left bottom mirror)
			)
		)
		(property "Description" "SMD Multilayer Ceramic Capacitor, 0.1 µF, 50 V, 0402 [1005 Metric], ± 10%, X5R, GRM Series"
			(at 0 0 180)
			(layer "F.Fab")
			(hide yes)
			(effects
				(font
					(size 1.27 1.27)
					(thickness 0.15)
				)
			)
		)
		(property "Author" "Antmicro"
			(at 331.490002 251.370002 0)
			(layer "B.Fab")
			(hide yes)
			(effects
				(font
					(size 1 1)
					(thickness 0.15)
				)
				(justify mirror)
			)
		)
		(property "Dielectric" "X5R"
			(at 331.490002 251.370002 0)
			(layer "B.Fab")
			(hide yes)
			(effects
				(font
					(size 1 1)
					(thickness 0.15)
				)
				(justify mirror)
			)
		)
		(property "License" "Apache-2.0"
			(at 331.490002 251.370002 0)
			(layer "B.Fab")
			(hide yes)
			(effects
				(font
					(size 1 1)
					(thickness 0.15)
				)
				(justify mirror)
			)
		)
		(property "MPN" "GRM155R61H104KE14D"
			(at 331.490002 251.370002 0)
			(layer "B.Fab")
			(hide yes)
			(effects
				(font
					(size 1 1)
					(thickness 0.15)
				)
				(justify mirror)
			)
		)
		(property "Manufacturer" "Murata"
			(at 331.490002 251.370002 0)
			(layer "B.Fab")
			(hide yes)
			(effects
				(font
					(size 1 1)
					(thickness 0.15)
				)
				(justify mirror)
			)
		)
		(property "Val" "100n"
			(at 331.490002 251.370002 0)
			(layer "B.Fab")
			(hide yes)
			(effects
				(font
					(size 1 1)
					(thickness 0.15)
				)
				(justify mirror)
			)
		)
		(property "Voltage" "50V"
			(at 331.490002 251.370002 0)
			(layer "B.Fab")
			(hide yes)
			(effects
				(font
					(size 1 1)
					(thickness 0.15)
				)
				(justify mirror)
			)
		)
		(sheetname "FMC+ HSPC")
		(sheetfile "fmc-hspc.kicad_sch")
		(attr smd)
		(fp_rect
			(start -0.925 0.47)
			(end 0.925 -0.47)
			(stroke
				(width 0.05)
				(type default)
			)
			(fill no)
			(layer "B.CrtYd")
		)
		(fp_line
			(start 0.504 0.25)
			(end 0.504 -0.248)
			(stroke
				(width 0.15)
				(type solid)
			)
			(layer "B.Fab")
		)
		(fp_line
			(start 0.504 -0.248)
			(end -0.494 -0.248)
			(stroke
				(width 0.15)
				(type solid)
			)
			(layer "B.Fab")
		)
		(fp_line
			(start -0.494 0.25)
			(end 0.504 0.25)
			(stroke
				(width 0.15)
				(type solid)
			)
			(layer "B.Fab")
		)
		(fp_line
			(start -0.494 -0.248)
			(end -0.494 0.25)
			(stroke
				(width 0.15)
				(type solid)
			)
			(layer "B.Fab")
		)
		(pad "1" smd roundrect
			(at -0.48 0 180)
			(size 0.59 0.64)
			(layers "B.Cu" "B.Mask" "B.Paste")
			(roundrect_rratio 0.25)
			(net 1 "GND")
			(pintype "passive")
		)
		(pad "2" smd roundrect
			(at 0.48 0 180)
			(size 0.59 0.64)
			(layers "B.Cu" "B.Mask" "B.Paste")
			(roundrect_rratio 0.25)
			(net 59 "12P0V")
			(pintype "passive")
		)
	)
	(footprint "antmicro-footprints:C_0402_1005Metric"
		(layer "B.Cu")
		(at 205 115.5 180)
		(descr "Capacitor SMD 0402")
		(tags "capacitor SMD 0402")
		(property "Reference" "C67"
			(at -1.1 0.475 0)
			(layer "B.SilkS")
			(effects
				(font
					(size 0.7 0.7)
					(thickness 0.15)
				)
				(justify left bottom mirror)
			)
		)
		(property "Value" "C_100n_0402"
			(at 0 -1.169 0)
			(layer "B.Fab")
			(effects
				(font
					(size 0.7 0.7)
					(thickness 0.15)
				)
				(justify left bottom mirror)
			)
		)
		(property "Description" "SMD Multilayer Ceramic Capacitor, 0.1 µF, 50 V, 0402 [1005 Metric], ± 10%, X5R, GRM Series"
			(at 0 0 180)
			(layer "F.Fab")
			(hide yes)
			(effects
				(font
					(size 1.27 1.27)
					(thickness 0.15)
				)
			)
		)
		(property "Author" "Antmicro"
			(at 410 231 0)
			(layer "B.Fab")
			(hide yes)
			(effects
				(font
					(size 1 1)
					(thickness 0.15)
				)
				(justify mirror)
			)
		)
		(property "Dielectric" "X5R"
			(at 410 231 0)
			(layer "B.Fab")
			(hide yes)
			(effects
				(font
					(size 1 1)
					(thickness 0.15)
				)
				(justify mirror)
			)
		)
		(property "License" "Apache-2.0"
			(at 410 231 0)
			(layer "B.Fab")
			(hide yes)
			(effects
				(font
					(size 1 1)
					(thickness 0.15)
				)
				(justify mirror)
			)
		)
		(property "MPN" "GRM155R61H104KE14D"
			(at 410 231 0)
			(layer "B.Fab")
			(hide yes)
			(effects
				(font
					(size 1 1)
					(thickness 0.15)
				)
				(justify mirror)
			)
		)
		(property "Manufacturer" "Murata"
			(at 410 231 0)
			(layer "B.Fab")
			(hide yes)
			(effects
				(font
					(size 1 1)
					(thickness 0.15)
				)
				(justify mirror)
			)
		)
		(property "Val" "100n"
			(at 410 231 0)
			(layer "B.Fab")
			(hide yes)
			(effects
				(font
					(size 1 1)
					(thickness 0.15)
				)
				(justify mirror)
			)
		)
		(property "Voltage" "50V"
			(at 410 231 0)
			(layer "B.Fab")
			(hide yes)
			(effects
				(font
					(size 1 1)
					(thickness 0.15)
				)
				(justify mirror)
			)
		)
		(sheetname "FPGA Bank 16 & 17")
		(sheetfile "fpga-bank-16-17.kicad_sch")
		(attr smd)
		(fp_rect
			(start -0.925 0.47)
			(end 0.925 -0.47)
			(stroke
				(width 0.05)
				(type default)
			)
			(fill no)
			(layer "B.CrtYd")
		)
		(fp_line
			(start 0.504 0.25)
			(end 0.504 -0.248)
			(stroke
				(width 0.15)
				(type solid)
			)
			(layer "B.Fab")
		)
		(fp_line
			(start 0.504 -0.248)
			(end -0.494 -0.248)
			(stroke
				(width 0.15)
				(type solid)
			)
			(layer "B.Fab")
		)
		(fp_line
			(start -0.494 0.25)
			(end 0.504 0.25)
			(stroke
				(width 0.15)
				(type solid)
			)
			(layer "B.Fab")
		)
		(fp_line
			(start -0.494 -0.248)
			(end -0.494 0.25)
			(stroke
				(width 0.15)
				(type solid)
			)
			(layer "B.Fab")
		)
		(pad "1" smd roundrect
			(at -0.48 0 180)
			(size 0.59 0.64)
			(layers "B.Cu" "B.Mask" "B.Paste")
			(roundrect_rratio 0.25)
			(net 1 "GND")
			(pintype "passive")
		)
		(pad "2" smd roundrect
			(at 0.48 0 180)
			(size 0.59 0.64)
			(layers "B.Cu" "B.Mask" "B.Paste")
			(roundrect_rratio 0.25)
			(net 24 "+3V3")
			(pintype "passive")
		)
	)
	(footprint "antmicro-footprints:Conn_JST_SH_1x4_BM04B-SRSS-TB-LF-SN"
		(layer "B.Cu")
		(at 239.101 113.775 180)
		(property "Reference" "J4"
			(at -1.399 3.075 0)
			(layer "B.SilkS")
			(effects
				(font
					(size 0.7 0.7)
					(thickness 0.15)
				)
				(justify left bottom mirror)
			)
		)
		(property "Value" "JST_SH_1x4_BM04B-SRSS-TB-LF-SN"
			(at 0 -3.1 0)
			(layer "B.Fab")
			(effects
				(font
					(size 0.7 0.7)
					(thickness 0.15)
				)
				(justify left bottom mirror)
			)
		)
		(property "Description" "Pin Header, Top Entry, Wire-to-Board, 1 mm, 1 Rows, 4 Contacts, Surface Mount, SR"
			(at 0 0 180)
			(layer "F.Fab")
			(hide yes)
			(effects
				(font
					(size 1.27 1.27)
					(thickness 0.15)
				)
			)
		)
		(property "Author" "Antmicro"
			(at 478.202 227.55 0)
			(layer "B.Fab")
			(hide yes)
			(effects
				(font
					(size 1 1)
					(thickness 0.15)
				)
				(justify mirror)
			)
		)
		(property "License" "Apache-2.0"
			(at 478.202 227.55 0)
			(layer "B.Fab")
			(hide yes)
			(effects
				(font
					(size 1 1)
					(thickness 0.15)
				)
				(justify mirror)
			)
		)
		(property "MPN" "BM04B-SRSS-TB(LF)(SN) "
			(at 478.202 227.55 0)
			(layer "B.Fab")
			(hide yes)
			(effects
				(font
					(size 1 1)
					(thickness 0.15)
				)
				(justify mirror)
			)
		)
		(property "Manufacturer" "JST Automotive Connectors"
			(at 478.202 227.55 0)
			(layer "B.Fab")
			(hide yes)
			(effects
				(font
					(size 1 1)
					(thickness 0.15)
				)
				(justify mirror)
			)
		)
		(sheetname "User GPIO + LED + button + DIP switch")
		(sheetfile "user-gpio.kicad_sch")
		(attr smd)
		(fp_line
			(start 1.774 1.7)
			(end 1.774 -1.702)
			(stroke
				(width 0.15)
				(type solid)
			)
			(layer "B.SilkS")
		)
		(fp_line
			(start -0.251 2.999)
			(end -1.125 2.999)
			(stroke
				(width 0.15)
				(type solid)
			)
			(layer "B.SilkS")
		)
		(fp_line
			(start -0.251 -2.999)
			(end -1.125 -2.999)
			(stroke
				(width 0.15)
				(type solid)
			)
			(layer "B.SilkS")
		)
		(fp_line
			(start -1.125 2.999)
			(end -1.125 2.201)
			(stroke
				(width 0.15)
				(type solid)
			)
			(layer "B.SilkS")
		)
		(fp_line
			(start -1.125 -2.999)
			(end -1.125 -2.201)
			(stroke
				(width 0.15)
				(type solid)
			)
			(layer "B.SilkS")
		)
		(fp_circle
			(center -1.6 2.1)
			(end -1.55 2.1)
			(stroke
				(width 0.15)
				(type solid)
			)
			(fill yes)
			(layer "B.SilkS")
		)
		(fp_rect
			(start -2.05 3.95)
			(end 2.05 -3.95)
			(stroke
				(width 0.05)
				(type solid)
			)
			(fill no)
			(layer "B.CrtYd")
		)
		(fp_rect
			(start -1.8 3)
			(end 1.8 -3)
			(stroke
				(width 0.15)
				(type solid)
			)
			(fill no)
			(layer "B.Fab")
		)
		(pad "1" smd roundrect
			(at -1.45 1.5 270)
			(size 0.6 1.55)
			(layers "B.Cu" "B.Mask" "B.Paste")
			(roundrect_rratio 0.25)
			(net 1 "GND")
			(pinfunction "Pin_1")
			(pintype "passive")
		)
		(pad "2" smd roundrect
			(at -1.45 0.5 270)
			(size 0.6 1.55)
			(layers "B.Cu" "B.Mask" "B.Paste")
			(roundrect_rratio 0.25)
			(net 703 "+5V")
			(pinfunction "Pin_2")
			(pintype "passive")
		)
		(pad "3" smd roundrect
			(at -1.45 -0.5 270)
			(size 0.6 1.55)
			(layers "B.Cu" "B.Mask" "B.Paste")
			(roundrect_rratio 0.25)
			(net 28 "unconnected-(J4-Pin_3-Pad3)")
			(pinfunction "Pin_3")
			(pintype "passive+no_connect")
		)
		(pad "4" smd roundrect
			(at -1.45 -1.5 270)
			(size 0.6 1.55)
			(layers "B.Cu" "B.Mask" "B.Paste")
			(roundrect_rratio 0.25)
			(net 29 "Net-(J4-Pin_4)")
			(pinfunction "Pin_4")
			(pintype "passive")
		)
		(pad "MP" smd roundrect
			(at 1.075 -2.8 270)
			(size 1.2 1.8)
			(layers "B.Cu" "B.Mask" "B.Paste")
			(roundrect_rratio 0.25)
			(net 1 "GND")
			(pinfunction "MP")
			(pintype "passive")
		)
		(pad "MP" smd roundrect
			(at 1.075 2.8 270)
			(size 1.2 1.8)
			(layers "B.Cu" "B.Mask" "B.Paste")
			(roundrect_rratio 0.25)
			(net 1 "GND")
			(pinfunction "MP")
			(pintype "passive")
		)
	)
)
